(kicad_pcb
	(version 20260206)
	(generator "pcbnew")
	(generator_version "10.0")
	(general
		(thickness 1.6)
		(legacy_teardrops no)
	)
	(paper "A4")
	(title_block
		(title "04192023_DAF0TMB3IC0_F0TG_MB_C_brd_V02_OCP.brd")
		(comment 1 "Grand Teton / footprints 4404-4407 of 8354")
	)
	(layers
		(0 "F.Cu" signal "TOP")
		(4 "In1.Cu" signal "GND")
		(6 "In2.Cu" signal "IN1")
		(8 "In3.Cu" signal "GND1")
		(10 "In4.Cu" signal "IN2")
		(12 "In5.Cu" signal "GND2")
		(14 "In6.Cu" signal "IN3")
		(16 "In7.Cu" signal "GND3")
		(18 "In8.Cu" signal "VCC")
		(20 "In9.Cu" signal "VCC1")
		(22 "In10.Cu" signal "GND4")
		(24 "In11.Cu" signal "IN4")
		(26 "In12.Cu" signal "GND5")
		(28 "In13.Cu" signal "IN5")
		(30 "In14.Cu" signal "GND6")
		(32 "In15.Cu" signal "IN6")
		(34 "In16.Cu" signal "GND7")
		(2 "B.Cu" signal "BOTTOM")
		(9 "F.Adhes" user "F.Adhesive")
		(11 "B.Adhes" user "B.Adhesive")
		(13 "F.Paste" user "Package Geometry/Pastemask Top")
		(15 "B.Paste" user "Package Geometry/Pastemask Bottom")
		(5 "F.SilkS" user "Ref Des/Silkscreen Top")
		(7 "B.SilkS" user "Ref Des/Silkscreen Bottom")
		(1 "F.Mask" user "Board Geometry/Soldermask Top")
		(3 "B.Mask" user "Board Geometry/Soldermask Bottom")
		(17 "Dwgs.User" user "User.Drawings")
		(19 "Cmts.User" user "User.Comments")
		(21 "Eco1.User" user "User.Eco1")
		(23 "Eco2.User" user "User.Eco2")
		(25 "Edge.Cuts" user "Board Geometry/Outline")
		(27 "Margin" user)
		(31 "F.CrtYd" user "Package Geometry/Place Bound Top")
		(29 "B.CrtYd" user "Package Geometry/Place Bound Bottom")
		(35 "F.Fab" user "Ref Des/Assembly Top")
		(33 "B.Fab" user "Ref Des/Assembly Bottom")
	)
	(footprint ""
		(layer "F.Cu")
		(at 302.133 -356.997 180)
		(property "Reference" "C305"
			(at 0 0 180)
			(layer "F.SilkS")
			(hide yes)
			(effects
				(font
					(size 1.27 1.27)
				)
			)
		)
		(property "Value" ""
			(at 0 0 180)
			(layer "F.Fab")
			(effects
				(font
					(size 1.27 1.27)
				)
			)
		)
		(duplicate_pad_numbers_are_jumpers no)
		(fp_line
			(start 0.7874 0.4064)
			(end -0.7874 0.4064)
			(stroke
				(width 0.1524)
				(type default)
			)
			(layer "F.SilkS")
		)
		(fp_line
			(start 0.7874 -0.4064)
			(end 0.7874 0.4064)
			(stroke
				(width 0.1524)
				(type default)
			)
			(layer "F.SilkS")
		)
		(fp_line
			(start -0.7874 0.4064)
			(end -0.7874 -0.4064)
			(stroke
				(width 0.1524)
				(type default)
			)
			(layer "F.SilkS")
		)
		(fp_line
			(start -0.7874 -0.4064)
			(end 0.7874 -0.4064)
			(stroke
				(width 0.1524)
				(type default)
			)
			(layer "F.SilkS")
		)
		(fp_line
			(start 0.67945 0.3048)
			(end 0.120396 0.3048)
			(stroke
				(width 0.1)
				(type default)
			)
			(layer "F.Fab")
		)
		(fp_line
			(start 0.67945 -0.3048)
			(end 0.67945 0.3048)
			(stroke
				(width 0.1)
				(type default)
			)
			(layer "F.Fab")
		)
		(fp_line
			(start 0.12065 -0.2794)
			(end 0.12065 -0.3048)
			(stroke
				(width 0.1)
				(type default)
			)
			(layer "F.Fab")
		)
		(fp_line
			(start 0.12065 -0.3048)
			(end 0.67945 -0.3048)
			(stroke
				(width 0.1)
				(type default)
			)
			(layer "F.Fab")
		)
		(fp_line
			(start 0.120396 0.3048)
			(end 0.120396 0.2794)
			(stroke
				(width 0.1)
				(type default)
			)
			(layer "F.Fab")
		)
		(fp_line
			(start 0.120396 0.2794)
			(end -0.12065 0.2794)
			(stroke
				(width 0.1)
				(type default)
			)
			(layer "F.Fab")
		)
		(fp_line
			(start -0.12065 0.3048)
			(end -0.67945 0.3048)
			(stroke
				(width 0.1)
				(type default)
			)
			(layer "F.Fab")
		)
		(fp_line
			(start -0.12065 0.2794)
			(end -0.12065 0.3048)
			(stroke
				(width 0.1)
				(type default)
			)
			(layer "F.Fab")
		)
		(fp_line
			(start -0.12065 -0.2794)
			(end 0.12065 -0.2794)
			(stroke
				(width 0.1)
				(type default)
			)
			(layer "F.Fab")
		)
		(fp_line
			(start -0.12065 -0.305054)
			(end -0.12065 -0.2794)
			(stroke
				(width 0.1)
				(type default)
			)
			(layer "F.Fab")
		)
		(fp_line
			(start -0.67945 0.3048)
			(end -0.67945 -0.305054)
			(stroke
				(width 0.1)
				(type default)
			)
			(layer "F.Fab")
		)
		(fp_line
			(start -0.67945 -0.305054)
			(end -0.12065 -0.305054)
			(stroke
				(width 0.1)
				(type default)
			)
			(layer "F.Fab")
		)
		(pad "1" smd circle
			(at -0.40005 0 180)
			(size 0 0)
			(layers "F.Cu" "F.Mask" "F.Paste")
			(net "SVID_PVDDCR_CPU1_P0_SVC_R")
		)
		(pad "2" smd circle
			(at 0.40005 0 180)
			(size 0 0)
			(layers "F.Cu" "F.Mask" "F.Paste")
			(net "GND")
		)
	)
	(footprint ""
		(layer "F.Cu")
		(at 106.246422 -409.63215 -90)
		(property "Reference" "U10"
			(at -0.080772 -3.860546 90)
			(unlocked yes)
			(layer "F.SilkS")
			(effects
				(font
					(size 0.7874 0.5842)
					(thickness 0.1524)
				)
			)
		)
		(property "Value" ""
			(at 0 0 270)
			(layer "F.Fab")
			(effects
				(font
					(size 1.27 1.27)
				)
			)
		)
		(duplicate_pad_numbers_are_jumpers no)
		(fp_line
			(start -2.500122 2.500122)
			(end -2.01676 2.500122)
			(stroke
				(width 0.1524)
				(type default)
			)
			(layer "F.SilkS")
		)
		(fp_line
			(start 2.01676 2.500122)
			(end 2.500122 2.500122)
			(stroke
				(width 0.1524)
				(type default)
			)
			(layer "F.SilkS")
		)
		(fp_line
			(start 2.500122 2.500122)
			(end 2.500122 2.01676)
			(stroke
				(width 0.1524)
				(type default)
			)
			(layer "F.SilkS")
		)
		(fp_line
			(start -2.500122 2.01676)
			(end -2.500122 2.500122)
			(stroke
				(width 0.1524)
				(type default)
			)
			(layer "F.SilkS")
		)
		(fp_line
			(start 2.500122 -2.01676)
			(end 2.500122 -2.500122)
			(stroke
				(width 0.1524)
				(type default)
			)
			(layer "F.SilkS")
		)
		(fp_line
			(start -2.500122 -2.500122)
			(end -2.500122 -2.01676)
			(stroke
				(width 0.1524)
				(type default)
			)
			(layer "F.SilkS")
		)
		(fp_line
			(start -2.01676 -2.500122)
			(end -2.500122 -2.500122)
			(stroke
				(width 0.1524)
				(type default)
			)
			(layer "F.SilkS")
		)
		(fp_line
			(start 2.500122 -2.500122)
			(end 2.01676 -2.500122)
			(stroke
				(width 0.1524)
				(type default)
			)
			(layer "F.SilkS")
		)
		(fp_poly
			(pts
				(xy -2.733294 -2.21615) (xy -4.065778 -2.318766) (xy -3.450844 -3.343656)
			)
			(stroke
				(width 0)
				(type default)
			)
			(fill yes)
			(layer "F.SilkS")
		)
		(fp_line
			(start -2.500122 2.500122)
			(end 2.500122 2.500122)
			(stroke
				(width 0.1)
				(type default)
			)
			(layer "F.Fab")
		)
		(fp_line
			(start 2.500122 2.500122)
			(end 2.500122 -2.500122)
			(stroke
				(width 0.1)
				(type default)
			)
			(layer "F.Fab")
		)
		(fp_line
			(start -2.500122 -2.500122)
			(end -2.500122 2.500122)
			(stroke
				(width 0.1)
				(type default)
			)
			(layer "F.Fab")
		)
		(fp_line
			(start 2.500122 -2.500122)
			(end -2.500122 -2.500122)
			(stroke
				(width 0.1)
				(type default)
			)
			(layer "F.Fab")
		)
		(fp_poly
			(pts
				(xy -3.044698 -1.75006) (xy -4.240022 -1.152398) (xy -4.240022 -2.347722)
			)
			(stroke
				(width 0)
				(type default)
			)
			(fill yes)
			(layer "F.Fab")
		)
		(pad "1" smd rect
			(at -2.3749 -1.75006 180)
			(size 0.254 0.5588)
			(layers "F.Cu" "F.Mask" "F.Paste")
			(net "FM_9ZXL045_P1_DEV_EN")
		)
		(pad "2" smd rect
			(at -2.3749 -1.249934 180)
			(size 0.254 0.5588)
			(layers "F.Cu" "F.Mask" "F.Paste")
			(net "P3V3_9ZXL045_P1_VDDR")
		)
		(pad "3" smd rect
			(at -2.3749 -0.750062 180)
			(size 0.254 0.5588)
			(layers "F.Cu" "F.Mask" "F.Paste")
			(net "CLK_100M_CPU1_CLK13_DP")
		)
		(pad "4" smd rect
			(at -2.3749 -0.249936 180)
			(size 0.254 0.5588)
			(layers "F.Cu" "F.Mask" "F.Paste")
			(net "CLK_100M_CPU1_CLK13_DN")
		)
		(pad "5" smd rect
			(at -2.3749 0.249936 180)
			(size 0.254 0.5588)
			(layers "F.Cu" "F.Mask" "F.Paste")
			(net "CLK_9ZXL045_P1_SADR0")
		)
		(pad "6" smd rect
			(at -2.3749 0.750062 180)
			(size 0.254 0.5588)
			(layers "F.Cu" "F.Mask" "F.Paste")
			(net "SMB_9ZXL045_P1_SDA")
		)
		(pad "7" smd rect
			(at -2.3749 1.249934 180)
			(size 0.254 0.5588)
			(layers "F.Cu" "F.Mask" "F.Paste")
			(net "SMB_9ZXL045_P1_SCL")
		)
		(pad "8" smd rect
			(at -2.3749 1.75006 180)
			(size 0.254 0.5588)
			(layers "F.Cu" "F.Mask" "F.Paste")
			(net "NC_U10_FBOUT_N")
		)
		(pad "9" smd rect
			(at -1.75006 2.3749 270)
			(size 0.254 0.5588)
			(layers "F.Cu" "F.Mask" "F.Paste")
			(net "NC_U10_FBOUT")
		)
		(pad "10" smd rect
			(at -1.249934 2.3749 270)
			(size 0.254 0.5588)
			(layers "F.Cu" "F.Mask" "F.Paste")
			(net "NC_U10_NC0")
		)
		(pad "11" smd rect
			(at -0.750062 2.3749 270)
			(size 0.254 0.5588)
			(layers "F.Cu" "F.Mask" "F.Paste")
			(net "NC_U10_NC1")
		)
		(pad "12" smd rect
			(at -0.249936 2.3749 270)
			(size 0.254 0.5588)
			(layers "F.Cu" "F.Mask" "F.Paste")
			(net "P3V3_9ZXL045_P1_VDD")
		)
		(pad "13" smd rect
			(at 0.249936 2.3749 270)
			(size 0.254 0.5588)
			(layers "F.Cu" "F.Mask" "F.Paste")
			(net "CLK_100M_RETIMER_CPU1_P0_R_DP")
		)
		(pad "14" smd rect
			(at 0.750062 2.3749 270)
			(size 0.254 0.5588)
			(layers "F.Cu" "F.Mask" "F.Paste")
			(net "CLK_100M_RETIMER_CPU1_P0_R_DN")
		)
		(pad "15" smd rect
			(at 1.249934 2.3749 270)
			(size 0.254 0.5588)
			(layers "F.Cu" "F.Mask" "F.Paste")
			(net "FM_9ZXL045_P1_0_OE_N")
		)
		(pad "16" smd rect
			(at 1.75006 2.3749 270)
			(size 0.254 0.5588)
			(layers "F.Cu" "F.Mask" "F.Paste")
			(net "P3V3_9ZXL045_P1_VDD")
		)
		(pad "17" smd rect
			(at 2.3749 1.75006)
			(size 0.254 0.5588)
			(layers "F.Cu" "F.Mask" "F.Paste")
			(net "NC_U10_NC2")
		)
		(pad "18" smd rect
			(at 2.3749 1.249934)
			(size 0.254 0.5588)
			(layers "F.Cu" "F.Mask" "F.Paste")
			(net "FM_9ZXL045_P1_1_OE_N")
		)
		(pad "19" smd rect
			(at 2.3749 0.750062)
			(size 0.254 0.5588)
			(layers "F.Cu" "F.Mask" "F.Paste")
			(net "CLK_100M_RETIMER_CPU1_P1_R_DP")
		)
		(pad "20" smd rect
			(at 2.3749 0.249936)
			(size 0.254 0.5588)
			(layers "F.Cu" "F.Mask" "F.Paste")
			(net "CLK_100M_RETIMER_CPU1_P1_R_DN")
		)
		(pad "21" smd rect
			(at 2.3749 -0.249936)
			(size 0.254 0.5588)
			(layers "F.Cu" "F.Mask" "F.Paste")
			(net "P3V3_9ZXL045_P1_VDD")
		)
		(pad "22" smd rect
			(at 2.3749 -0.750062)
			(size 0.254 0.5588)
			(layers "F.Cu" "F.Mask" "F.Paste")
			(net "CLK_100M_RETIMER_CPU1_P2_R_DP")
		)
		(pad "23" smd rect
			(at 2.3749 -1.249934)
			(size 0.254 0.5588)
			(layers "F.Cu" "F.Mask" "F.Paste")
			(net "CLK_100M_RETIMER_CPU1_P2_R_DN")
		)
		(pad "24" smd rect
			(at 2.3749 -1.75006)
			(size 0.254 0.5588)
			(layers "F.Cu" "F.Mask" "F.Paste")
			(net "FM_9ZXL045_P1_2_OE_N")
		)
		(pad "25" smd rect
			(at 1.75006 -2.3749 90)
			(size 0.254 0.5588)
			(layers "F.Cu" "F.Mask" "F.Paste")
			(net "P3V3_9ZXL045_P1_VDD")
		)
		(pad "26" smd rect
			(at 1.249934 -2.3749 90)
			(size 0.254 0.5588)
			(layers "F.Cu" "F.Mask" "F.Paste")
			(net "FM_9ZXL045_P1_3_OE_N")
		)
		(pad "27" smd rect
			(at 0.750062 -2.3749 90)
			(size 0.254 0.5588)
			(layers "F.Cu" "F.Mask" "F.Paste")
			(net "CLK_100M_RETIMER_CPU1_P3_R_DP")
		)
		(pad "28" smd rect
			(at 0.249936 -2.3749 90)
			(size 0.254 0.5588)
			(layers "F.Cu" "F.Mask" "F.Paste")
			(net "CLK_100M_RETIMER_CPU1_P3_R_DN")
		)
		(pad "29" smd rect
			(at -0.249936 -2.3749 90)
			(size 0.254 0.5588)
			(layers "F.Cu" "F.Mask" "F.Paste")
			(net "P3V3_9ZXL045_P1_VDD")
		)
		(pad "30" smd rect
			(at -0.750062 -2.3749 90)
			(size 0.254 0.5588)
			(layers "F.Cu" "F.Mask" "F.Paste")
			(net "NC_U10_NC3")
		)
		(pad "31" smd rect
			(at -1.249934 -2.3749 90)
			(size 0.254 0.5588)
			(layers "F.Cu" "F.Mask" "F.Paste")
			(net "P3V3_9ZXL045_P1_VDDA")
		)
		(pad "32" smd rect
			(at -1.75006 -2.3749 90)
			(size 0.254 0.5588)
			(layers "F.Cu" "F.Mask" "F.Paste")
			(net "CLK_9ZXL045_P1_HIBW")
		)
		(pad "33" smd rect
			(at 0 0 270)
			(size 3.1496 3.1496)
			(layers "F.Cu" "F.Mask" "F.Paste")
			(net "GND")
		)
		(zone
			(layer "F.Cu")
			(hatch none 0.5)
			(connect_pads
				(clearance 0)
			)
			(min_thickness 0.25)
			(keepout
				(tracks not_allowed)
				(vias allowed)
				(pads allowed)
				(copperpour not_allowed)
				(footprints allowed)
			)
			(placement
				(enabled no)
				(sheetname "")
			)
			(fill
				(thermal_gap 0.5)
				(thermal_bridge_width 0.5)
				(island_removal_mode 0)
			)
			(polygon
				(pts
					(xy 104.201722 -411.67685) (xy 107.470956 -411.67685) (xy 107.470956 -411.25775) (xy 104.620822 -411.25775)
					(xy 104.620822 -408.00655) (xy 107.872022 -408.00655) (xy 107.872022 -411.25775) (xy 107.496356 -411.25775)
					(xy 107.496356 -411.67685) (xy 108.291122 -411.67685) (xy 108.291122 -407.58745) (xy 104.201722 -407.58745)
				)
			)
		)
	)
	(footprint ""
		(layer "F.Cu")
		(at 446.359788 -32.174434 -90)
		(property "Reference" "R591"
			(at 0 0 270)
			(layer "F.SilkS")
			(hide yes)
			(effects
				(font
					(size 1.27 1.27)
				)
			)
		)
		(property "Value" ""
			(at 0 0 270)
			(layer "F.Fab")
			(effects
				(font
					(size 1.27 1.27)
				)
			)
		)
		(duplicate_pad_numbers_are_jumpers no)
		(fp_line
			(start -0.7874 0.4064)
			(end -0.7874 -0.4064)
			(stroke
				(width 0.1524)
				(type default)
			)
			(layer "F.SilkS")
		)
		(fp_line
			(start 0.7874 0.4064)
			(end -0.7874 0.4064)
			(stroke
				(width 0.1524)
				(type default)
			)
			(layer "F.SilkS")
		)
		(fp_line
			(start -0.7874 -0.4064)
			(end 0.7874 -0.4064)
			(stroke
				(width 0.1524)
				(type default)
			)
			(layer "F.SilkS")
		)
		(fp_line
			(start 0.7874 -0.4064)
			(end 0.7874 0.4064)
			(stroke
				(width 0.1524)
				(type default)
			)
			(layer "F.SilkS")
		)
		(fp_line
			(start -0.67945 0.3048)
			(end -0.67945 -0.305054)
			(stroke
				(width 0.1)
				(type default)
			)
			(layer "F.Fab")
		)
		(fp_line
			(start -0.12065 0.3048)
			(end -0.67945 0.3048)
			(stroke
				(width 0.1)
				(type default)
			)
			(layer "F.Fab")
		)
		(fp_line
			(start 0.120396 0.3048)
			(end 0.120396 0.2794)
			(stroke
				(width 0.1)
				(type default)
			)
			(layer "F.Fab")
		)
		(fp_line
			(start 0.67945 0.3048)
			(end 0.120396 0.3048)
			(stroke
				(width 0.1)
				(type default)
			)
			(layer "F.Fab")
		)
		(fp_line
			(start -0.12065 0.2794)
			(end -0.12065 0.3048)
			(stroke
				(width 0.1)
				(type default)
			)
			(layer "F.Fab")
		)
		(fp_line
			(start 0.120396 0.2794)
			(end -0.12065 0.2794)
			(stroke
				(width 0.1)
				(type default)
			)
			(layer "F.Fab")
		)
		(fp_line
			(start -0.12065 -0.2794)
			(end 0.12065 -0.2794)
			(stroke
				(width 0.1)
				(type default)
			)
			(layer "F.Fab")
		)
		(fp_line
			(start 0.12065 -0.2794)
			(end 0.12065 -0.3048)
			(stroke
				(width 0.1)
				(type default)
			)
			(layer "F.Fab")
		)
		(fp_line
			(start 0.12065 -0.3048)
			(end 0.67945 -0.3048)
			(stroke
				(width 0.1)
				(type default)
			)
			(layer "F.Fab")
		)
		(fp_line
			(start 0.67945 -0.3048)
			(end 0.67945 0.3048)
			(stroke
				(width 0.1)
				(type default)
			)
			(layer "F.Fab")
		)
		(fp_line
			(start -0.67945 -0.305054)
			(end -0.12065 -0.305054)
			(stroke
				(width 0.1)
				(type default)
			)
			(layer "F.Fab")
		)
		(fp_line
			(start -0.12065 -0.305054)
			(end -0.12065 -0.2794)
			(stroke
				(width 0.1)
				(type default)
			)
			(layer "F.Fab")
		)
		(pad "1" smd circle
			(at -0.40005 0 270)
			(size 0 0)
			(layers "F.Cu" "F.Mask" "F.Paste")
			(net "P12V_OCP_SFF_BUF_EN_R")
		)
		(pad "2" smd circle
			(at 0.40005 0 270)
			(size 0 0)
			(layers "F.Cu" "F.Mask" "F.Paste")
			(net "P12V_OCP_EN_1_R2")
		)
	)
	(footprint ""
		(layer "F.Cu")
		(at 351.938844 -381.41783 -90)
		(property "Reference" "C943"
			(at 0 0 270)
			(layer "F.SilkS")
			(hide yes)
			(effects
				(font
					(size 1.27 1.27)
				)
			)
		)
		(property "Value" ""
			(at 0 0 270)
			(layer "F.Fab")
			(effects
				(font
					(size 1.27 1.27)
				)
			)
		)
		(duplicate_pad_numbers_are_jumpers no)
		(fp_line
			(start -0.299974 0.150114)
			(end -0.299974 -0.150114)
			(stroke
				(width 0.1)
				(type default)
			)
			(layer "F.Fab")
		)
		(fp_line
			(start 0.299974 0.150114)
			(end -0.299974 0.150114)
			(stroke
				(width 0.1)
				(type default)
			)
			(layer "F.Fab")
		)
		(fp_line
			(start -0.299974 -0.150114)
			(end 0.299974 -0.150114)
			(stroke
				(width 0.1)
				(type default)
			)
			(layer "F.Fab")
		)
		(fp_line
			(start 0.299974 -0.150114)
			(end 0.299974 0.150114)
			(stroke
				(width 0.1)
				(type default)
			)
			(layer "F.Fab")
		)
		(pad "1" smd rect
			(at -0.2667 0 270)
			(size 0.3048 0.381)
			(layers "F.Cu" "F.Mask" "F.Paste")
			(net "P5E_CPU0_P1_TX_C_DP<11>")
		)
		(pad "2" smd rect
			(at 0.2667 0 270)
			(size 0.3048 0.381)
			(layers "F.Cu" "F.Mask" "F.Paste")
			(net "P5E_CPU0_P1_TX_DP<11>")
		)
	)
)
